(kicad_pcb
	(version 20260206)
	(generator "pcbnew")
	(generator_version "10.0")
	(general
		(thickness 1.6)
		(legacy_teardrops no)
	)
	(paper "A4")
	(title_block
		(title "9054_F0T_PDB_BD_GPU_F_V04_1213_1550_OCP.brd")
		(comment 1 "Grand Teton / footprints 211-215 of 608")
	)
	(layers
		(0 "F.Cu" signal "TOP")
		(4 "In1.Cu" signal "GND")
		(6 "In2.Cu" signal "IN1")
		(8 "In3.Cu" signal "GND1")
		(10 "In4.Cu" signal "VCC")
		(12 "In5.Cu" signal "VCC1")
		(14 "In6.Cu" signal "GND2")
		(16 "In7.Cu" signal "IN2")
		(18 "In8.Cu" signal "GND3")
		(2 "B.Cu" signal "BOTTOM")
		(9 "F.Adhes" user "F.Adhesive")
		(11 "B.Adhes" user "B.Adhesive")
		(13 "F.Paste" user "Package Geometry/Pastemask Top")
		(15 "B.Paste" user "Package Geometry/Pastemask Bottom")
		(5 "F.SilkS" user "Ref Des/Silkscreen Top")
		(7 "B.SilkS" user "Ref Des/Silkscreen Bottom")
		(1 "F.Mask" user "Board Geometry/Soldermask Top")
		(3 "B.Mask" user "Board Geometry/Soldermask Bottom")
		(17 "Dwgs.User" user "User.Drawings")
		(19 "Cmts.User" user "User.Comments")
		(21 "Eco1.User" user "User.Eco1")
		(23 "Eco2.User" user "User.Eco2")
		(25 "Edge.Cuts" user "Board Geometry/Outline")
		(27 "Margin" user)
		(31 "F.CrtYd" user "Package Geometry/Place Bound Top")
		(29 "B.CrtYd" user "Package Geometry/Place Bound Bottom")
		(35 "F.Fab" user "Ref Des/Assembly Top")
		(33 "B.Fab" user "Ref Des/Assembly Bottom")
	)
	(footprint ""
		(layer "F.Cu")
		(at 166.543736 -66.167 180)
		(property "Reference" "R5894"
			(at 0 0 180)
			(layer "F.SilkS")
			(hide yes)
			(effects
				(font
					(size 1.27 1.27)
				)
			)
		)
		(property "Value" ""
			(at 0 0 180)
			(layer "F.Fab")
			(effects
				(font
					(size 1.27 1.27)
				)
			)
		)
		(duplicate_pad_numbers_are_jumpers no)
		(fp_line
			(start 0.7874 0.4064)
			(end -0.7874 0.4064)
			(stroke
				(width 0.1524)
				(type default)
			)
			(layer "F.SilkS")
		)
		(fp_line
			(start 0.7874 -0.4064)
			(end 0.7874 0.4064)
			(stroke
				(width 0.1524)
				(type default)
			)
			(layer "F.SilkS")
		)
		(fp_line
			(start -0.7874 0.4064)
			(end -0.7874 -0.4064)
			(stroke
				(width 0.1524)
				(type default)
			)
			(layer "F.SilkS")
		)
		(fp_line
			(start -0.7874 -0.4064)
			(end 0.7874 -0.4064)
			(stroke
				(width 0.1524)
				(type default)
			)
			(layer "F.SilkS")
		)
		(fp_line
			(start 0.67945 0.3048)
			(end 0.120396 0.3048)
			(stroke
				(width 0.1)
				(type default)
			)
			(layer "F.Fab")
		)
		(fp_line
			(start 0.67945 -0.3048)
			(end 0.67945 0.3048)
			(stroke
				(width 0.1)
				(type default)
			)
			(layer "F.Fab")
		)
		(fp_line
			(start 0.12065 -0.2794)
			(end 0.12065 -0.3048)
			(stroke
				(width 0.1)
				(type default)
			)
			(layer "F.Fab")
		)
		(fp_line
			(start 0.12065 -0.3048)
			(end 0.67945 -0.3048)
			(stroke
				(width 0.1)
				(type default)
			)
			(layer "F.Fab")
		)
		(fp_line
			(start 0.120396 0.3048)
			(end 0.120396 0.2794)
			(stroke
				(width 0.1)
				(type default)
			)
			(layer "F.Fab")
		)
		(fp_line
			(start 0.120396 0.2794)
			(end -0.12065 0.2794)
			(stroke
				(width 0.1)
				(type default)
			)
			(layer "F.Fab")
		)
		(fp_line
			(start -0.12065 0.3048)
			(end -0.67945 0.3048)
			(stroke
				(width 0.1)
				(type default)
			)
			(layer "F.Fab")
		)
		(fp_line
			(start -0.12065 0.2794)
			(end -0.12065 0.3048)
			(stroke
				(width 0.1)
				(type default)
			)
			(layer "F.Fab")
		)
		(fp_line
			(start -0.12065 -0.2794)
			(end 0.12065 -0.2794)
			(stroke
				(width 0.1)
				(type default)
			)
			(layer "F.Fab")
		)
		(fp_line
			(start -0.12065 -0.305054)
			(end -0.12065 -0.2794)
			(stroke
				(width 0.1)
				(type default)
			)
			(layer "F.Fab")
		)
		(fp_line
			(start -0.67945 0.3048)
			(end -0.67945 -0.305054)
			(stroke
				(width 0.1)
				(type default)
			)
			(layer "F.Fab")
		)
		(fp_line
			(start -0.67945 -0.305054)
			(end -0.12065 -0.305054)
			(stroke
				(width 0.1)
				(type default)
			)
			(layer "F.Fab")
		)
		(pad "1" smd circle
			(at -0.40005 0 180)
			(size 0 0)
			(layers "F.Cu" "F.Mask" "F.Paste")
			(net "P52V_HS2_ADR0")
		)
		(pad "2" smd circle
			(at 0.40005 0 180)
			(size 0 0)
			(layers "F.Cu" "F.Mask" "F.Paste")
			(net "GND1_FIELD_SIGNAL")
		)
	)
	(footprint ""
		(layer "F.Cu")
		(at 379.660912 -17.907254 -90)
		(property "Reference" "R71"
			(at 0 0 270)
			(layer "F.SilkS")
			(hide yes)
			(effects
				(font
					(size 1.27 1.27)
				)
			)
		)
		(property "Value" ""
			(at 0 0 270)
			(layer "F.Fab")
			(effects
				(font
					(size 1.27 1.27)
				)
			)
		)
		(duplicate_pad_numbers_are_jumpers no)
		(fp_line
			(start -0.7874 0.4064)
			(end -0.7874 -0.4064)
			(stroke
				(width 0.1524)
				(type default)
			)
			(layer "F.SilkS")
		)
		(fp_line
			(start 0.7874 0.4064)
			(end -0.7874 0.4064)
			(stroke
				(width 0.1524)
				(type default)
			)
			(layer "F.SilkS")
		)
		(fp_line
			(start -0.7874 -0.4064)
			(end 0.7874 -0.4064)
			(stroke
				(width 0.1524)
				(type default)
			)
			(layer "F.SilkS")
		)
		(fp_line
			(start 0.7874 -0.4064)
			(end 0.7874 0.4064)
			(stroke
				(width 0.1524)
				(type default)
			)
			(layer "F.SilkS")
		)
		(fp_line
			(start -0.67945 0.3048)
			(end -0.67945 -0.305054)
			(stroke
				(width 0.1)
				(type default)
			)
			(layer "F.Fab")
		)
		(fp_line
			(start -0.12065 0.3048)
			(end -0.67945 0.3048)
			(stroke
				(width 0.1)
				(type default)
			)
			(layer "F.Fab")
		)
		(fp_line
			(start 0.120396 0.3048)
			(end 0.120396 0.2794)
			(stroke
				(width 0.1)
				(type default)
			)
			(layer "F.Fab")
		)
		(fp_line
			(start 0.67945 0.3048)
			(end 0.120396 0.3048)
			(stroke
				(width 0.1)
				(type default)
			)
			(layer "F.Fab")
		)
		(fp_line
			(start -0.12065 0.2794)
			(end -0.12065 0.3048)
			(stroke
				(width 0.1)
				(type default)
			)
			(layer "F.Fab")
		)
		(fp_line
			(start 0.120396 0.2794)
			(end -0.12065 0.2794)
			(stroke
				(width 0.1)
				(type default)
			)
			(layer "F.Fab")
		)
		(fp_line
			(start -0.12065 -0.2794)
			(end 0.12065 -0.2794)
			(stroke
				(width 0.1)
				(type default)
			)
			(layer "F.Fab")
		)
		(fp_line
			(start 0.12065 -0.2794)
			(end 0.12065 -0.3048)
			(stroke
				(width 0.1)
				(type default)
			)
			(layer "F.Fab")
		)
		(fp_line
			(start 0.12065 -0.3048)
			(end 0.67945 -0.3048)
			(stroke
				(width 0.1)
				(type default)
			)
			(layer "F.Fab")
		)
		(fp_line
			(start 0.67945 -0.3048)
			(end 0.67945 0.3048)
			(stroke
				(width 0.1)
				(type default)
			)
			(layer "F.Fab")
		)
		(fp_line
			(start -0.67945 -0.305054)
			(end -0.12065 -0.305054)
			(stroke
				(width 0.1)
				(type default)
			)
			(layer "F.Fab")
		)
		(fp_line
			(start -0.12065 -0.305054)
			(end -0.12065 -0.2794)
			(stroke
				(width 0.1)
				(type default)
			)
			(layer "F.Fab")
		)
		(pad "1" smd circle
			(at -0.40005 0 270)
			(size 0 0)
			(layers "F.Cu" "F.Mask" "F.Paste")
			(net "SMB_PDB_FAN_0_SCL")
		)
		(pad "2" smd circle
			(at 0.40005 0 270)
			(size 0 0)
			(layers "F.Cu" "F.Mask" "F.Paste")
			(net "SMB_PDB_FAN_0_R_SCL")
		)
	)
	(footprint ""
		(layer "F.Cu")
		(at 428.00016 -4.499864 180)
		(property "Reference" "H14"
			(at 1.15316 10.586466 0)
			(unlocked yes)
			(layer "F.SilkS")
			(effects
				(font
					(size 0.7874 0.5842)
					(thickness 0.1524)
				)
				(justify left)
			)
		)
		(property "Value" ""
			(at 0 0 180)
			(layer "F.Fab")
			(effects
				(font
					(size 1.27 1.27)
				)
			)
		)
		(duplicate_pad_numbers_are_jumpers no)
		(pad "1" thru_hole oval
			(at 0 0 180)
			(size 9.017 14.0208)
			(drill 3.0226
				(offset 0 2.499868)
			)
			(layers "*.Cu" "*.Mask")
			(remove_unused_layers no)
			(net "GND")
			(clearance -1.500378)
			(padstack
				(mode front_inner_back)
				(layer "Inner"
					(shape circle)
					(size 0 0)
					(clearance 0)
				)
				(layer "B.Cu"
					(shape oval)
					(size 9.017 14.0208)
					(offset 0 2.499868)
					(clearance -1.500378)
				)
			)
		)
	)
	(footprint ""
		(layer "F.Cu")
		(at 413.45358 -32.75076 90)
		(property "Reference" "R5926"
			(at 0 0 90)
			(layer "F.SilkS")
			(hide yes)
			(effects
				(font
					(size 1.27 1.27)
				)
			)
		)
		(property "Value" ""
			(at 0 0 90)
			(layer "F.Fab")
			(effects
				(font
					(size 1.27 1.27)
				)
			)
		)
		(duplicate_pad_numbers_are_jumpers no)
		(fp_line
			(start 0.7874 -0.4064)
			(end 0.7874 0.4064)
			(stroke
				(width 0.1524)
				(type default)
			)
			(layer "F.SilkS")
		)
		(fp_line
			(start -0.7874 -0.4064)
			(end 0.7874 -0.4064)
			(stroke
				(width 0.1524)
				(type default)
			)
			(layer "F.SilkS")
		)
		(fp_line
			(start 0.7874 0.4064)
			(end -0.7874 0.4064)
			(stroke
				(width 0.1524)
				(type default)
			)
			(layer "F.SilkS")
		)
		(fp_line
			(start -0.7874 0.4064)
			(end -0.7874 -0.4064)
			(stroke
				(width 0.1524)
				(type default)
			)
			(layer "F.SilkS")
		)
		(fp_line
			(start -0.12065 -0.305054)
			(end -0.12065 -0.2794)
			(stroke
				(width 0.1)
				(type default)
			)
			(layer "F.Fab")
		)
		(fp_line
			(start -0.67945 -0.305054)
			(end -0.12065 -0.305054)
			(stroke
				(width 0.1)
				(type default)
			)
			(layer "F.Fab")
		)
		(fp_line
			(start 0.67945 -0.3048)
			(end 0.67945 0.3048)
			(stroke
				(width 0.1)
				(type default)
			)
			(layer "F.Fab")
		)
		(fp_line
			(start 0.12065 -0.3048)
			(end 0.67945 -0.3048)
			(stroke
				(width 0.1)
				(type default)
			)
			(layer "F.Fab")
		)
		(fp_line
			(start 0.12065 -0.2794)
			(end 0.12065 -0.3048)
			(stroke
				(width 0.1)
				(type default)
			)
			(layer "F.Fab")
		)
		(fp_line
			(start -0.12065 -0.2794)
			(end 0.12065 -0.2794)
			(stroke
				(width 0.1)
				(type default)
			)
			(layer "F.Fab")
		)
		(fp_line
			(start 0.120396 0.2794)
			(end -0.12065 0.2794)
			(stroke
				(width 0.1)
				(type default)
			)
			(layer "F.Fab")
		)
		(fp_line
			(start -0.12065 0.2794)
			(end -0.12065 0.3048)
			(stroke
				(width 0.1)
				(type default)
			)
			(layer "F.Fab")
		)
		(fp_line
			(start 0.67945 0.3048)
			(end 0.120396 0.3048)
			(stroke
				(width 0.1)
				(type default)
			)
			(layer "F.Fab")
		)
		(fp_line
			(start 0.120396 0.3048)
			(end 0.120396 0.2794)
			(stroke
				(width 0.1)
				(type default)
			)
			(layer "F.Fab")
		)
		(fp_line
			(start -0.12065 0.3048)
			(end -0.67945 0.3048)
			(stroke
				(width 0.1)
				(type default)
			)
			(layer "F.Fab")
		)
		(fp_line
			(start -0.67945 0.3048)
			(end -0.67945 -0.305054)
			(stroke
				(width 0.1)
				(type default)
			)
			(layer "F.Fab")
		)
		(pad "1" smd circle
			(at -0.40005 0 90)
			(size 0 0)
			(layers "F.Cu" "F.Mask" "F.Paste")
			(net "P12V_LED_IMON")
		)
		(pad "2" smd circle
			(at 0.40005 0 90)
			(size 0 0)
			(layers "F.Cu" "F.Mask" "F.Paste")
			(net "GND")
		)
	)
	(footprint ""
		(layer "F.Cu")
		(at 447.421 -46.101 180)
		(property "Reference" "C26"
			(at 0 0 180)
			(layer "F.SilkS")
			(hide yes)
			(effects
				(font
					(size 1.27 1.27)
				)
			)
		)
		(property "Value" ""
			(at 0 0 180)
			(layer "F.Fab")
			(effects
				(font
					(size 1.27 1.27)
				)
			)
		)
		(duplicate_pad_numbers_are_jumpers no)
		(fp_line
			(start 0.7874 0.4064)
			(end -0.7874 0.4064)
			(stroke
				(width 0.1524)
				(type default)
			)
			(layer "F.SilkS")
		)
		(fp_line
			(start 0.7874 -0.4064)
			(end 0.7874 0.4064)
			(stroke
				(width 0.1524)
				(type default)
			)
			(layer "F.SilkS")
		)
		(fp_line
			(start -0.7874 0.4064)
			(end -0.7874 -0.4064)
			(stroke
				(width 0.1524)
				(type default)
			)
			(layer "F.SilkS")
		)
		(fp_line
			(start -0.7874 -0.4064)
			(end 0.7874 -0.4064)
			(stroke
				(width 0.1524)
				(type default)
			)
			(layer "F.SilkS")
		)
		(fp_line
			(start 0.67945 0.3048)
			(end 0.120396 0.3048)
			(stroke
				(width 0.1)
				(type default)
			)
			(layer "F.Fab")
		)
		(fp_line
			(start 0.67945 -0.3048)
			(end 0.67945 0.3048)
			(stroke
				(width 0.1)
				(type default)
			)
			(layer "F.Fab")
		)
		(fp_line
			(start 0.12065 -0.2794)
			(end 0.12065 -0.3048)
			(stroke
				(width 0.1)
				(type default)
			)
			(layer "F.Fab")
		)
		(fp_line
			(start 0.12065 -0.3048)
			(end 0.67945 -0.3048)
			(stroke
				(width 0.1)
				(type default)
			)
			(layer "F.Fab")
		)
		(fp_line
			(start 0.120396 0.3048)
			(end 0.120396 0.2794)
			(stroke
				(width 0.1)
				(type default)
			)
			(layer "F.Fab")
		)
		(fp_line
			(start 0.120396 0.2794)
			(end -0.12065 0.2794)
			(stroke
				(width 0.1)
				(type default)
			)
			(layer "F.Fab")
		)
		(fp_line
			(start -0.12065 0.3048)
			(end -0.67945 0.3048)
			(stroke
				(width 0.1)
				(type default)
			)
			(layer "F.Fab")
		)
		(fp_line
			(start -0.12065 0.2794)
			(end -0.12065 0.3048)
			(stroke
				(width 0.1)
				(type default)
			)
			(layer "F.Fab")
		)
		(fp_line
			(start -0.12065 -0.2794)
			(end 0.12065 -0.2794)
			(stroke
				(width 0.1)
				(type default)
			)
			(layer "F.Fab")
		)
		(fp_line
			(start -0.12065 -0.305054)
			(end -0.12065 -0.2794)
			(stroke
				(width 0.1)
				(type default)
			)
			(layer "F.Fab")
		)
		(fp_line
			(start -0.67945 0.3048)
			(end -0.67945 -0.305054)
			(stroke
				(width 0.1)
				(type default)
			)
			(layer "F.Fab")
		)
		(fp_line
			(start -0.67945 -0.305054)
			(end -0.12065 -0.305054)
			(stroke
				(width 0.1)
				(type default)
			)
			(layer "F.Fab")
		)
		(pad "1" smd circle
			(at -0.40005 0 180)
			(size 0 0)
			(layers "F.Cu" "F.Mask" "F.Paste")
			(net "GND")
		)
		(pad "2" smd circle
			(at 0.40005 0 180)
			(size 0 0)
			(layers "F.Cu" "F.Mask" "F.Paste")
			(net "P3V3_AUX")
		)
	)
)
